(kicad_pcb
	(version 20260206)
	(generator "pcbnew")
	(generator_version "10.0")
	(general
		(thickness 1.6)
		(legacy_teardrops no)
	)
	(paper "A4")
	(title_block
		(title "01162023_DA0F0TEBIF0_F0T_Expander_BD_F_brd_V02_OCP.brd")
		(comment 1 "Grand Teton / footprints 5288-5294 of 9728")
	)
	(layers
		(0 "F.Cu" signal "TOP")
		(4 "In1.Cu" signal "GND")
		(6 "In2.Cu" signal "VCC")
		(8 "In3.Cu" signal "VCC1")
		(10 "In4.Cu" signal "GND1")
		(12 "In5.Cu" signal "IN1")
		(14 "In6.Cu" signal "GND2")
		(16 "In7.Cu" signal "IN2")
		(18 "In8.Cu" signal "GND3")
		(20 "In9.Cu" signal "IN3")
		(22 "In10.Cu" signal "GND4")
		(24 "In11.Cu" signal "IN4")
		(26 "In12.Cu" signal "GND5")
		(28 "In13.Cu" signal "IN5")
		(30 "In14.Cu" signal "GND6")
		(32 "In15.Cu" signal "IN6")
		(34 "In16.Cu" signal "GND7")
		(2 "B.Cu" signal "BOTTOM")
		(9 "F.Adhes" user "F.Adhesive")
		(11 "B.Adhes" user "B.Adhesive")
		(13 "F.Paste" user "Package Geometry/Pastemask Top")
		(15 "B.Paste" user "Package Geometry/Pastemask Bottom")
		(5 "F.SilkS" user "Ref Des/Silkscreen Top")
		(7 "B.SilkS" user "Ref Des/Silkscreen Bottom")
		(1 "F.Mask" user "Board Geometry/Soldermask Top")
		(3 "B.Mask" user "Board Geometry/Soldermask Bottom")
		(17 "Dwgs.User" user "User.Drawings")
		(19 "Cmts.User" user "User.Comments")
		(21 "Eco1.User" user "User.Eco1")
		(23 "Eco2.User" user "User.Eco2")
		(25 "Edge.Cuts" user "Board Geometry/Outline")
		(27 "Margin" user)
		(31 "F.CrtYd" user "Package Geometry/Place Bound Top")
		(29 "B.CrtYd" user "Package Geometry/Place Bound Bottom")
		(35 "F.Fab" user "Ref Des/Assembly Top")
		(33 "B.Fab" user "Ref Des/Assembly Bottom")
	)
	(footprint ""
		(layer "F.Cu")
		(at 55.872126 -32.848042 90)
		(property "Reference" "PC680"
			(at 0 0 90)
			(layer "F.SilkS")
			(hide yes)
			(effects
				(font
					(size 1.27 1.27)
				)
			)
		)
		(property "Value" ""
			(at 0 0 90)
			(layer "F.Fab")
			(effects
				(font
					(size 1.27 1.27)
				)
			)
		)
		(duplicate_pad_numbers_are_jumpers no)
		(fp_line
			(start 0.7874 -0.4064)
			(end 0.7874 0.4064)
			(stroke
				(width 0.1524)
				(type default)
			)
			(layer "F.SilkS")
		)
		(fp_line
			(start -0.7874 -0.4064)
			(end 0.7874 -0.4064)
			(stroke
				(width 0.1524)
				(type default)
			)
			(layer "F.SilkS")
		)
		(fp_line
			(start 0.7874 0.4064)
			(end -0.7874 0.4064)
			(stroke
				(width 0.1524)
				(type default)
			)
			(layer "F.SilkS")
		)
		(fp_line
			(start -0.7874 0.4064)
			(end -0.7874 -0.4064)
			(stroke
				(width 0.1524)
				(type default)
			)
			(layer "F.SilkS")
		)
		(fp_line
			(start -0.12065 -0.305054)
			(end -0.12065 -0.2794)
			(stroke
				(width 0.1)
				(type default)
			)
			(layer "F.Fab")
		)
		(fp_line
			(start -0.67945 -0.305054)
			(end -0.12065 -0.305054)
			(stroke
				(width 0.1)
				(type default)
			)
			(layer "F.Fab")
		)
		(fp_line
			(start 0.67945 -0.3048)
			(end 0.67945 0.3048)
			(stroke
				(width 0.1)
				(type default)
			)
			(layer "F.Fab")
		)
		(fp_line
			(start 0.12065 -0.3048)
			(end 0.67945 -0.3048)
			(stroke
				(width 0.1)
				(type default)
			)
			(layer "F.Fab")
		)
		(fp_line
			(start 0.12065 -0.2794)
			(end 0.12065 -0.3048)
			(stroke
				(width 0.1)
				(type default)
			)
			(layer "F.Fab")
		)
		(fp_line
			(start -0.12065 -0.2794)
			(end 0.12065 -0.2794)
			(stroke
				(width 0.1)
				(type default)
			)
			(layer "F.Fab")
		)
		(fp_line
			(start 0.120396 0.2794)
			(end -0.12065 0.2794)
			(stroke
				(width 0.1)
				(type default)
			)
			(layer "F.Fab")
		)
		(fp_line
			(start -0.12065 0.2794)
			(end -0.12065 0.3048)
			(stroke
				(width 0.1)
				(type default)
			)
			(layer "F.Fab")
		)
		(fp_line
			(start 0.67945 0.3048)
			(end 0.120396 0.3048)
			(stroke
				(width 0.1)
				(type default)
			)
			(layer "F.Fab")
		)
		(fp_line
			(start 0.120396 0.3048)
			(end 0.120396 0.2794)
			(stroke
				(width 0.1)
				(type default)
			)
			(layer "F.Fab")
		)
		(fp_line
			(start -0.12065 0.3048)
			(end -0.67945 0.3048)
			(stroke
				(width 0.1)
				(type default)
			)
			(layer "F.Fab")
		)
		(fp_line
			(start -0.67945 0.3048)
			(end -0.67945 -0.305054)
			(stroke
				(width 0.1)
				(type default)
			)
			(layer "F.Fab")
		)
		(pad "1" smd circle
			(at -0.40005 0 90)
			(size 0 0)
			(layers "F.Cu" "F.Mask" "F.Paste")
			(net "P3V3_SSD2_CO_GATE")
		)
		(pad "2" smd circle
			(at 0.40005 0 90)
			(size 0 0)
			(layers "F.Cu" "F.Mask" "F.Paste")
			(net "GND")
		)
	)
	(footprint ""
		(layer "F.Cu")
		(at 266.310364 -63.652146 180)
		(property "Reference" "R5997"
			(at 0 0 180)
			(layer "F.SilkS")
			(hide yes)
			(effects
				(font
					(size 1.27 1.27)
				)
			)
		)
		(property "Value" ""
			(at 0 0 180)
			(layer "F.Fab")
			(effects
				(font
					(size 1.27 1.27)
				)
			)
		)
		(duplicate_pad_numbers_are_jumpers no)
		(fp_line
			(start 0.7874 0.4064)
			(end -0.7874 0.4064)
			(stroke
				(width 0.1524)
				(type default)
			)
			(layer "F.SilkS")
		)
		(fp_line
			(start 0.7874 -0.4064)
			(end 0.7874 0.4064)
			(stroke
				(width 0.1524)
				(type default)
			)
			(layer "F.SilkS")
		)
		(fp_line
			(start -0.7874 0.4064)
			(end -0.7874 -0.4064)
			(stroke
				(width 0.1524)
				(type default)
			)
			(layer "F.SilkS")
		)
		(fp_line
			(start -0.7874 -0.4064)
			(end 0.7874 -0.4064)
			(stroke
				(width 0.1524)
				(type default)
			)
			(layer "F.SilkS")
		)
		(fp_line
			(start 0.67945 0.3048)
			(end 0.120396 0.3048)
			(stroke
				(width 0.1)
				(type default)
			)
			(layer "F.Fab")
		)
		(fp_line
			(start 0.67945 -0.3048)
			(end 0.67945 0.3048)
			(stroke
				(width 0.1)
				(type default)
			)
			(layer "F.Fab")
		)
		(fp_line
			(start 0.12065 -0.2794)
			(end 0.12065 -0.3048)
			(stroke
				(width 0.1)
				(type default)
			)
			(layer "F.Fab")
		)
		(fp_line
			(start 0.12065 -0.3048)
			(end 0.67945 -0.3048)
			(stroke
				(width 0.1)
				(type default)
			)
			(layer "F.Fab")
		)
		(fp_line
			(start 0.120396 0.3048)
			(end 0.120396 0.2794)
			(stroke
				(width 0.1)
				(type default)
			)
			(layer "F.Fab")
		)
		(fp_line
			(start 0.120396 0.2794)
			(end -0.12065 0.2794)
			(stroke
				(width 0.1)
				(type default)
			)
			(layer "F.Fab")
		)
		(fp_line
			(start -0.12065 0.3048)
			(end -0.67945 0.3048)
			(stroke
				(width 0.1)
				(type default)
			)
			(layer "F.Fab")
		)
		(fp_line
			(start -0.12065 0.2794)
			(end -0.12065 0.3048)
			(stroke
				(width 0.1)
				(type default)
			)
			(layer "F.Fab")
		)
		(fp_line
			(start -0.12065 -0.2794)
			(end 0.12065 -0.2794)
			(stroke
				(width 0.1)
				(type default)
			)
			(layer "F.Fab")
		)
		(fp_line
			(start -0.12065 -0.305054)
			(end -0.12065 -0.2794)
			(stroke
				(width 0.1)
				(type default)
			)
			(layer "F.Fab")
		)
		(fp_line
			(start -0.67945 0.3048)
			(end -0.67945 -0.305054)
			(stroke
				(width 0.1)
				(type default)
			)
			(layer "F.Fab")
		)
		(fp_line
			(start -0.67945 -0.305054)
			(end -0.12065 -0.305054)
			(stroke
				(width 0.1)
				(type default)
			)
			(layer "F.Fab")
		)
		(pad "1" smd circle
			(at -0.40005 0 180)
			(size 0 0)
			(layers "F.Cu" "F.Mask" "F.Paste")
			(net "P5V_AUX")
		)
		(pad "2" smd circle
			(at 0.40005 0 180)
			(size 0 0)
			(layers "F.Cu" "F.Mask" "F.Paste")
			(net "P12V_SSD9_PG_G2")
		)
	)
	(footprint ""
		(layer "F.Cu")
		(at 231.30383 -307.484272)
		(property "Reference" "PJ12"
			(at 0 0 0)
			(layer "F.SilkS")
			(hide yes)
			(effects
				(font
					(size 1.27 1.27)
				)
			)
		)
		(property "Value" ""
			(at 0 0 0)
			(layer "F.Fab")
			(effects
				(font
					(size 1.27 1.27)
				)
			)
		)
		(duplicate_pad_numbers_are_jumpers no)
		(pad "1" smd circle
			(at -0.40005 0 90)
			(size 0 0)
			(layers "F.Cu" "F.Mask" "F.Paste")
			(net "SH_P1V25_PEX1_FB_N")
		)
		(pad "2" smd rect
			(at 0.40005 0 180)
			(size 0.4572 0.508)
			(layers "F.Cu" "F.Mask" "F.Paste")
			(net "GND")
		)
		(zone
			(layer "F.Cu")
			(hatch none 0.5)
			(connect_pads
				(clearance 0)
			)
			(min_thickness 0.25)
			(keepout
				(tracks allowed)
				(vias not_allowed)
				(pads allowed)
				(copperpour not_allowed)
				(footprints allowed)
			)
			(placement
				(enabled no)
				(sheetname "")
			)
			(fill
				(thermal_gap 0.5)
				(thermal_bridge_width 0.5)
				(island_removal_mode 0)
			)
			(polygon
				(pts
					(xy 230.61803 -307.179472) (xy 231.98963 -307.179472) (xy 231.98963 -307.789072) (xy 230.61803 -307.789072)
				)
			)
		)
	)
	(footprint ""
		(layer "F.Cu")
		(at 289.789362 -63.56223)
		(property "Reference" "Q206"
			(at 0.024638 -1.8161 0)
			(unlocked yes)
			(layer "F.SilkS")
			(effects
				(font
					(size 0.7874 0.5842)
					(thickness 0.1524)
				)
			)
		)
		(property "Value" ""
			(at 0 0 0)
			(layer "F.Fab")
			(effects
				(font
					(size 1.27 1.27)
				)
			)
		)
		(duplicate_pad_numbers_are_jumpers no)
		(fp_line
			(start -1.376172 -1.199896)
			(end -0.508 -1.199896)
			(stroke
				(width 0.1524)
				(type default)
			)
			(layer "F.SilkS")
		)
		(fp_line
			(start -1.376172 1.199896)
			(end -1.376172 -1.199896)
			(stroke
				(width 0.1524)
				(type default)
			)
			(layer "F.SilkS")
		)
		(fp_line
			(start -0.508 -1.199896)
			(end 0 -0.762)
			(stroke
				(width 0.1524)
				(type default)
			)
			(layer "F.SilkS")
		)
		(fp_line
			(start 0 -0.762)
			(end 0.508 -1.199896)
			(stroke
				(width 0.1524)
				(type default)
			)
			(layer "F.SilkS")
		)
		(fp_line
			(start 0.508 -1.199896)
			(end 1.376172 -1.199896)
			(stroke
				(width 0.1524)
				(type default)
			)
			(layer "F.SilkS")
		)
		(fp_line
			(start 1.376172 -1.199896)
			(end 1.376172 1.199896)
			(stroke
				(width 0.1524)
				(type default)
			)
			(layer "F.SilkS")
		)
		(fp_line
			(start 1.376172 1.199896)
			(end -1.376172 1.199896)
			(stroke
				(width 0.1524)
				(type default)
			)
			(layer "F.SilkS")
		)
		(fp_poly
			(pts
				(xy -1.493774 -1.180084) (xy -1.763268 -1.988312) (xy -2.302002 -1.449578)
			)
			(stroke
				(width 0)
				(type default)
			)
			(fill yes)
			(layer "F.SilkS")
		)
		(fp_line
			(start -0.674878 -1.100074)
			(end 0.674878 -1.100074)
			(stroke
				(width 0.1)
				(type default)
			)
			(layer "F.Fab")
		)
		(fp_line
			(start -0.674878 1.100074)
			(end -0.674878 -1.100074)
			(stroke
				(width 0.1)
				(type default)
			)
			(layer "F.Fab")
		)
		(fp_line
			(start 0.674878 -1.100074)
			(end 0.674878 1.100074)
			(stroke
				(width 0.1)
				(type default)
			)
			(layer "F.Fab")
		)
		(fp_line
			(start 0.674878 1.100074)
			(end -0.674878 1.100074)
			(stroke
				(width 0.1)
				(type default)
			)
			(layer "F.Fab")
		)
		(fp_poly
			(pts
				(xy -1.4605 -0.7493) (xy -2.2225 -1.1303) (xy -2.2225 -0.3683)
			)
			(stroke
				(width 0)
				(type default)
			)
			(fill yes)
			(layer "F.Fab")
		)
		(pad "1" smd rect
			(at -0.899922 -0.750062 270)
			(size 0.6096 0.6096)
			(layers "F.Cu" "F.Mask" "F.Paste")
			(net "GND")
		)
		(pad "2" smd rect
			(at -0.899922 0 270)
			(size 0.4064 0.6096)
			(layers "F.Cu" "F.Mask" "F.Paste")
			(net "P12V_SSD10_PG_G1")
		)
		(pad "3" smd rect
			(at -0.899922 0.750062 270)
			(size 0.6096 0.6096)
			(layers "F.Cu" "F.Mask" "F.Paste")
			(net "PWRGD_P12V_SSD10_D")
		)
		(pad "4" smd rect
			(at 0.899922 0.750062 270)
			(size 0.6096 0.6096)
			(layers "F.Cu" "F.Mask" "F.Paste")
			(net "GND")
		)
		(pad "5" smd rect
			(at 0.899922 0 270)
			(size 0.4064 0.6096)
			(layers "F.Cu" "F.Mask" "F.Paste")
			(net "P12V_SSD10_PG_G2")
		)
		(pad "6" smd rect
			(at 0.899922 -0.750062 270)
			(size 0.6096 0.6096)
			(layers "F.Cu" "F.Mask" "F.Paste")
			(net "P12V_SSD10_PG_G2")
		)
	)
	(footprint ""
		(layer "F.Cu")
		(at 304.455068 -35.876738)
		(property "Reference" "R6093"
			(at 0 0 0)
			(layer "F.SilkS")
			(hide yes)
			(effects
				(font
					(size 1.27 1.27)
				)
			)
		)
		(property "Value" ""
			(at 0 0 0)
			(layer "F.Fab")
			(effects
				(font
					(size 1.27 1.27)
				)
			)
		)
		(duplicate_pad_numbers_are_jumpers no)
		(fp_line
			(start -0.7874 -0.4064)
			(end 0.7874 -0.4064)
			(stroke
				(width 0.1524)
				(type default)
			)
			(layer "F.SilkS")
		)
		(fp_line
			(start -0.7874 0.4064)
			(end -0.7874 -0.4064)
			(stroke
				(width 0.1524)
				(type default)
			)
			(layer "F.SilkS")
		)
		(fp_line
			(start 0.7874 -0.4064)
			(end 0.7874 0.4064)
			(stroke
				(width 0.1524)
				(type default)
			)
			(layer "F.SilkS")
		)
		(fp_line
			(start 0.7874 0.4064)
			(end -0.7874 0.4064)
			(stroke
				(width 0.1524)
				(type default)
			)
			(layer "F.SilkS")
		)
		(fp_line
			(start -0.67945 -0.305054)
			(end -0.12065 -0.305054)
			(stroke
				(width 0.1)
				(type default)
			)
			(layer "F.Fab")
		)
		(fp_line
			(start -0.67945 0.3048)
			(end -0.67945 -0.305054)
			(stroke
				(width 0.1)
				(type default)
			)
			(layer "F.Fab")
		)
		(fp_line
			(start -0.12065 -0.305054)
			(end -0.12065 -0.2794)
			(stroke
				(width 0.1)
				(type default)
			)
			(layer "F.Fab")
		)
		(fp_line
			(start -0.12065 -0.2794)
			(end 0.12065 -0.2794)
			(stroke
				(width 0.1)
				(type default)
			)
			(layer "F.Fab")
		)
		(fp_line
			(start -0.12065 0.2794)
			(end -0.12065 0.3048)
			(stroke
				(width 0.1)
				(type default)
			)
			(layer "F.Fab")
		)
		(fp_line
			(start -0.12065 0.3048)
			(end -0.67945 0.3048)
			(stroke
				(width 0.1)
				(type default)
			)
			(layer "F.Fab")
		)
		(fp_line
			(start 0.120396 0.2794)
			(end -0.12065 0.2794)
			(stroke
				(width 0.1)
				(type default)
			)
			(layer "F.Fab")
		)
		(fp_line
			(start 0.120396 0.3048)
			(end 0.120396 0.2794)
			(stroke
				(width 0.1)
				(type default)
			)
			(layer "F.Fab")
		)
		(fp_line
			(start 0.12065 -0.3048)
			(end 0.67945 -0.3048)
			(stroke
				(width 0.1)
				(type default)
			)
			(layer "F.Fab")
		)
		(fp_line
			(start 0.12065 -0.2794)
			(end 0.12065 -0.3048)
			(stroke
				(width 0.1)
				(type default)
			)
			(layer "F.Fab")
		)
		(fp_line
			(start 0.67945 -0.3048)
			(end 0.67945 0.3048)
			(stroke
				(width 0.1)
				(type default)
			)
			(layer "F.Fab")
		)
		(fp_line
			(start 0.67945 0.3048)
			(end 0.120396 0.3048)
			(stroke
				(width 0.1)
				(type default)
			)
			(layer "F.Fab")
		)
		(pad "1" smd circle
			(at -0.40005 0)
			(size 0 0)
			(layers "F.Cu" "F.Mask" "F.Paste")
			(net "P3V3_AUX")
		)
		(pad "2" smd circle
			(at 0.40005 0)
			(size 0 0)
			(layers "F.Cu" "F.Mask" "F.Paste")
			(net "PWRGD_P3V3_SSD11_D")
		)
	)
	(footprint ""
		(layer "F.Cu")
		(at 387.580632 -132.215382)
		(property "Reference" "C670"
			(at 0 0 0)
			(layer "F.SilkS")
			(hide yes)
			(effects
				(font
					(size 1.27 1.27)
				)
			)
		)
		(property "Value" ""
			(at 0 0 0)
			(layer "F.Fab")
			(effects
				(font
					(size 1.27 1.27)
				)
			)
		)
		(duplicate_pad_numbers_are_jumpers no)
		(fp_line
			(start -0.299974 -0.150114)
			(end 0.299974 -0.150114)
			(stroke
				(width 0.1)
				(type default)
			)
			(layer "F.Fab")
		)
		(fp_line
			(start -0.299974 0.150114)
			(end -0.299974 -0.150114)
			(stroke
				(width 0.1)
				(type default)
			)
			(layer "F.Fab")
		)
		(fp_line
			(start 0.299974 -0.150114)
			(end 0.299974 0.150114)
			(stroke
				(width 0.1)
				(type default)
			)
			(layer "F.Fab")
		)
		(fp_line
			(start 0.299974 0.150114)
			(end -0.299974 0.150114)
			(stroke
				(width 0.1)
				(type default)
			)
			(layer "F.Fab")
		)
		(pad "1" smd rect
			(at -0.2667 0)
			(size 0.3048 0.381)
			(layers "F.Cu" "F.Mask" "F.Paste")
			(net "P5E_PEX3_STN1_TX_DN<29>")
		)
		(pad "2" smd rect
			(at 0.2667 0)
			(size 0.3048 0.381)
			(layers "F.Cu" "F.Mask" "F.Paste")
			(net "P5E_PEX3_STN1_TX_C_DN<29>")
		)
	)
	(footprint ""
		(layer "F.Cu")
		(at 378.453396 -284.990032)
		(property "Reference" "L143"
			(at 0 0 0)
			(layer "F.SilkS")
			(hide yes)
			(effects
				(font
					(size 1.27 1.27)
				)
			)
		)
		(property "Value" ""
			(at 0 0 0)
			(layer "F.Fab")
			(effects
				(font
					(size 1.27 1.27)
				)
			)
		)
		(duplicate_pad_numbers_are_jumpers no)
		(fp_line
			(start -1.63576 -0.8128)
			(end -1.63576 0.8128)
			(stroke
				(width 0.1524)
				(type default)
			)
			(layer "F.SilkS")
		)
		(fp_line
			(start -1.63576 -0.8128)
			(end 1.63576 -0.8128)
			(stroke
				(width 0.1524)
				(type default)
			)
			(layer "F.SilkS")
		)
		(fp_line
			(start 1.63576 -0.8128)
			(end 1.63576 0.8128)
			(stroke
				(width 0.1524)
				(type default)
			)
			(layer "F.SilkS")
		)
		(fp_line
			(start 1.63576 0.8128)
			(end -1.63576 0.8128)
			(stroke
				(width 0.1524)
				(type default)
			)
			(layer "F.SilkS")
		)
		(fp_line
			(start -1.56083 -0.738632)
			(end -1.56083 0.7366)
			(stroke
				(width 0.1)
				(type default)
			)
			(layer "F.Fab")
		)
		(fp_line
			(start -1.56083 0.7366)
			(end -1.524 0.7366)
			(stroke
				(width 0.1)
				(type default)
			)
			(layer "F.Fab")
		)
		(fp_line
			(start -1.524 0.7366)
			(end 1.524 0.7366)
			(stroke
				(width 0.1)
				(type default)
			)
			(layer "F.Fab")
		)
		(fp_line
			(start 1.524 0.7366)
			(end 1.560576 0.7366)
			(stroke
				(width 0.1)
				(type default)
			)
			(layer "F.Fab")
		)
		(fp_line
			(start 1.560576 -0.738632)
			(end -1.56083 -0.738632)
			(stroke
				(width 0.1)
				(type default)
			)
			(layer "F.Fab")
		)
		(fp_line
			(start 1.560576 0.7366)
			(end 1.560576 -0.738632)
			(stroke
				(width 0.1)
				(type default)
			)
			(layer "F.Fab")
		)
		(pad "1" smd rect
			(at -0.94996 0 180)
			(size 1.1176 1.3716)
			(layers "F.Cu" "F.Mask" "F.Paste")
			(net "P1V8_PLL0_PEX3")
		)
		(pad "2" smd rect
			(at 0.94996 0 180)
			(size 1.1176 1.3716)
			(layers "F.Cu" "F.Mask" "F.Paste")
			(net "PCEPLL7_VDDA18_PEX3")
		)
	)
)
